# BASEBOARD_FAB2 (Tioga Pass) — schematic netlist excerpt (pin names and nets, part order shuffled) for the footprints in the layout excerpt that follows; sources: Cadence DE-HDL packaged netlist, KiCad conversion of Wiwynn_Tioga_Pass_MB.brd

Q1P2  FET_N  2N7002 FET  pkg SOT23LF  page 196
  GATE  = PWRGD_P5V_N
  SRC  = GND
  DRN  = PWRGD_P5V_R

R9A3  RES  0.0 5% CHIP  pkg 0402  page 111 : A = XDP_PCH_CPU_TCK0 ; B = XDP_CPU_TCK0
R6U14  RES  20.0 1% CHIP  pkg 0402  page 99 : A = SMB_DDR_GHJ_VPP_SDA_R ; B = SMB_DDR_GHJ_VPP_SDA

(kicad_pcb
	(version 20260206)
	(generator "pcbnew")
	(generator_version "10.0")
	(general
		(thickness 1.6)
		(legacy_teardrops no)
	)
	(paper "A4")
	(title_block
		(title "Wiwynn_Tioga_Pass_MB.brd")
		(comment 1 "Tioga Pass / footprints 2679-2681 of 4770")
	)
	(layers
		(0 "F.Cu" signal "TOP")
		(4 "In1.Cu" signal "L2GND")
		(6 "In2.Cu" signal "L3")
		(8 "In3.Cu" signal "L4GND")
		(10 "In4.Cu" signal "L5")
		(12 "In5.Cu" signal "L6GND")
		(14 "In6.Cu" signal "L7VCC")
		(16 "In7.Cu" signal "L8VCC")
		(18 "In8.Cu" signal "L9GND")
		(20 "In9.Cu" signal "L10")
		(22 "In10.Cu" signal "L11GND")
		(24 "In11.Cu" signal "L12")
		(26 "In12.Cu" signal "L13GND")
		(2 "B.Cu" signal "BOTTOM")
		(9 "F.Adhes" user "F.Adhesive")
		(11 "B.Adhes" user "B.Adhesive")
		(13 "F.Paste" user "Package Geometry/Pastemask Top")
		(15 "B.Paste" user "Package Geometry/Pastemask Bottom")
		(5 "F.SilkS" user "Ref Des/Silkscreen Top")
		(7 "B.SilkS" user "Ref Des/Silkscreen Bottom")
		(1 "F.Mask" user "Board Geometry/Soldermask Top")
		(3 "B.Mask" user "Board Geometry/Soldermask Bottom")
		(17 "Dwgs.User" user "User.Drawings")
		(19 "Cmts.User" user "User.Comments")
		(21 "Eco1.User" user "User.Eco1")
		(23 "Eco2.User" user "User.Eco2")
		(25 "Edge.Cuts" user "Board Geometry/Outline")
		(27 "Margin" user)
		(31 "F.CrtYd" user "Package Geometry/Place Bound Top")
		(29 "B.CrtYd" user "Package Geometry/Place Bound Bottom")
		(35 "F.Fab" user "Ref Des/Assembly Top")
		(33 "B.Fab" user "Ref Des/Assembly Bottom")
	)
	(footprint ""
		(layer "B.Cu")
		(at 413.639 -6.1976 180)
		(property "Reference" "Q1P2"
			(at 0.229362 -1.2065 180)
			(unlocked yes)
			(layer "B.SilkS")
			(effects
				(font
					(size 0.4064 0.254)
					(thickness 0.1524)
				)
				(justify left mirror)
			)
		)
		(property "Value" ""
			(at 0 0 0)
			(layer "B.Fab")
			(effects
				(font
					(size 1.27 1.27)
				)
				(justify mirror)
			)
		)
		(duplicate_pad_numbers_are_jumpers no)
		(fp_line
			(start -0.381 0.635)
			(end -0.381 1.27)
			(stroke
				(width 0.1524)
				(type default)
			)
			(layer "B.SilkS")
		)
		(fp_line
			(start -0.9525 2.4765)
			(end -1.778 2.4765)
			(stroke
				(width 0.1524)
				(type default)
			)
			(layer "B.SilkS")
		)
		(fp_line
			(start -0.9525 -0.5715)
			(end -1.778 -0.5715)
			(stroke
				(width 0.1524)
				(type default)
			)
			(layer "B.SilkS")
		)
		(fp_line
			(start -1.778 2.4765)
			(end -1.778 1.5875)
			(stroke
				(width 0.1524)
				(type default)
			)
			(layer "B.SilkS")
		)
		(fp_line
			(start -1.778 -0.5715)
			(end -1.778 0.3175)
			(stroke
				(width 0.1524)
				(type default)
			)
			(layer "B.SilkS")
		)
		(fp_circle
			(center 0.9525 -0.9271)
			(end 0.8255 -0.9271)
			(stroke
				(width 0.254)
				(type default)
			)
			(fill no)
			(layer "B.SilkS")
		)
		(fp_poly
			(pts
				(xy -1.778 2.4765) (xy -0.381 2.4765) (xy -0.381 -0.5715) (xy -1.778 -0.5715)
			)
			(stroke
				(width 0)
				(type default)
			)
			(fill no)
			(layer "B.CrtYd")
		)
		(fp_line
			(start -0.381 2.4765)
			(end -1.778 2.4765)
			(stroke
				(width 0.1)
				(type default)
			)
			(layer "B.Fab")
		)
		(fp_line
			(start -0.381 -0.5715)
			(end -0.381 2.4765)
			(stroke
				(width 0.1)
				(type default)
			)
			(layer "B.Fab")
		)
		(fp_line
			(start -1.778 2.4765)
			(end -1.778 -0.5715)
			(stroke
				(width 0.1)
				(type default)
			)
			(layer "B.Fab")
		)
		(fp_line
			(start -1.778 -0.5715)
			(end -0.381 -0.5715)
			(stroke
				(width 0.1)
				(type default)
			)
			(layer "B.Fab")
		)
		(fp_circle
			(center 0.9525 -0.9271)
			(end 0.8255 -0.9271)
			(stroke
				(width 0.254)
				(type default)
			)
			(fill no)
			(layer "B.Fab")
		)
		(pad "1" smd rect
			(at 0 0)
			(size 1.143 0.508)
			(layers "B.Cu" "B.Mask" "B.Paste")
			(net "PWRGD_P5V_N")
		)
		(pad "2" smd rect
			(at 0 1.905)
			(size 1.143 0.508)
			(layers "B.Cu" "B.Mask" "B.Paste")
			(net "GND")
		)
		(pad "3" smd rect
			(at -2.159 0.9525)
			(size 1.143 0.508)
			(layers "B.Cu" "B.Mask" "B.Paste")
			(net "PWRGD_P5V_R")
		)
	)
	(footprint ""
		(layer "B.Cu")
		(at 452.8058 -153.6446 180)
		(property "Reference" "R9A3"
			(at 0 0 0)
			(layer "B.SilkS")
			(hide yes)
			(effects
				(font
					(size 1.27 1.27)
				)
				(justify mirror)
			)
		)
		(property "Value" ""
			(at 0 0 0)
			(layer "B.Fab")
			(effects
				(font
					(size 1.27 1.27)
				)
				(justify mirror)
			)
		)
		(duplicate_pad_numbers_are_jumpers no)
		(fp_poly
			(pts
				(xy 0.2794 -0.1016) (xy -0.2794 -0.1016) (xy -0.2794 0.9906) (xy 0.2794 0.9906)
			)
			(stroke
				(width 0)
				(type default)
			)
			(fill no)
			(layer "B.CrtYd")
		)
		(fp_line
			(start 0.2794 0.9906)
			(end -0.2794 0.9906)
			(stroke
				(width 0.1)
				(type default)
			)
			(layer "B.Fab")
		)
		(fp_line
			(start 0.2794 -0.1016)
			(end 0.2794 0.9906)
			(stroke
				(width 0.1)
				(type default)
			)
			(layer "B.Fab")
		)
		(fp_line
			(start -0.2794 0.9906)
			(end -0.2794 -0.1016)
			(stroke
				(width 0.1)
				(type default)
			)
			(layer "B.Fab")
		)
		(fp_line
			(start -0.2794 -0.1016)
			(end 0.2794 -0.1016)
			(stroke
				(width 0.1)
				(type default)
			)
			(layer "B.Fab")
		)
		(pad "1" smd rect
			(at 0 0)
			(size 0.508 0.508)
			(layers "B.Cu" "B.Mask" "B.Paste")
			(net "XDP_PCH_CPU_TCK0")
		)
		(pad "2" smd rect
			(at 0 0.889)
			(size 0.508 0.508)
			(layers "B.Cu" "B.Mask" "B.Paste")
			(net "XDP_CPU_TCK0")
		)
		(zone
			(layer "B.Cu")
			(hatch none 0.5)
			(connect_pads
				(clearance 0)
			)
			(min_thickness 0.25)
			(keepout
				(tracks not_allowed)
				(vias allowed)
				(pads allowed)
				(copperpour not_allowed)
				(footprints allowed)
			)
			(placement
				(enabled no)
				(sheetname "")
			)
			(fill
				(thermal_gap 0.5)
				(thermal_bridge_width 0.5)
				(island_removal_mode 0)
			)
			(polygon
				(pts
					(xy 452.5518 -154.2796) (xy 453.0598 -154.2796) (xy 453.0598 -153.8986) (xy 452.5518 -153.8986)
				)
			)
		)
		(zone
			(layer "B.Cu")
			(hatch none 0.5)
			(connect_pads
				(clearance 0)
			)
			(min_thickness 0.25)
			(keepout
				(tracks allowed)
				(vias not_allowed)
				(pads allowed)
				(copperpour not_allowed)
				(footprints allowed)
			)
			(placement
				(enabled no)
				(sheetname "")
			)
			(fill
				(thermal_gap 0.5)
				(thermal_bridge_width 0.5)
				(island_removal_mode 0)
			)
			(polygon
				(pts
					(xy 452.5518 -153.8986) (xy 453.0598 -153.8986) (xy 453.0598 -154.2796) (xy 452.5518 -154.2796)
				)
			)
		)
	)
	(footprint ""
		(layer "B.Cu")
		(at 165.8874 2.286 -90)
		(property "Reference" "R6U14"
			(at 0 0 90)
			(layer "B.SilkS")
			(hide yes)
			(effects
				(font
					(size 1.27 1.27)
				)
				(justify mirror)
			)
		)
		(property "Value" ""
			(at 0 0 90)
			(layer "B.Fab")
			(effects
				(font
					(size 1.27 1.27)
				)
				(justify mirror)
			)
		)
		(duplicate_pad_numbers_are_jumpers no)
		(fp_poly
			(pts
				(xy 0.2794 -0.1016) (xy -0.2794 -0.1016) (xy -0.2794 0.9906) (xy 0.2794 0.9906)
			)
			(stroke
				(width 0)
				(type default)
			)
			(fill no)
			(layer "B.CrtYd")
		)
		(fp_line
			(start -0.2794 0.9906)
			(end -0.2794 -0.1016)
			(stroke
				(width 0.1)
				(type default)
			)
			(layer "B.Fab")
		)
		(fp_line
			(start 0.2794 0.9906)
			(end -0.2794 0.9906)
			(stroke
				(width 0.1)
				(type default)
			)
			(layer "B.Fab")
		)
		(fp_line
			(start -0.2794 -0.1016)
			(end 0.2794 -0.1016)
			(stroke
				(width 0.1)
				(type default)
			)
			(layer "B.Fab")
		)
		(fp_line
			(start 0.2794 -0.1016)
			(end 0.2794 0.9906)
			(stroke
				(width 0.1)
				(type default)
			)
			(layer "B.Fab")
		)
		(pad "1" smd rect
			(at 0 0 90)
			(size 0.508 0.508)
			(layers "B.Cu" "B.Mask" "B.Paste")
			(net "SMB_DDR_GHJ_VPP_SDA_R")
		)
		(pad "2" smd rect
			(at 0 0.889 90)
			(size 0.508 0.508)
			(layers "B.Cu" "B.Mask" "B.Paste")
			(net "SMB_DDR_GHJ_VPP_SDA")
		)
		(zone
			(layer "B.Cu")
			(hatch none 0.5)
			(connect_pads
				(clearance 0)
			)
			(min_thickness 0.25)
			(keepout
				(tracks not_allowed)
				(vias allowed)
				(pads allowed)
				(copperpour not_allowed)
				(footprints allowed)
			)
			(placement
				(enabled no)
				(sheetname "")
			)
			(fill
				(thermal_gap 0.5)
				(thermal_bridge_width 0.5)
				(island_removal_mode 0)
			)
			(polygon
				(pts
					(xy 165.2524 2.54) (xy 165.2524 2.032) (xy 165.6334 2.032) (xy 165.6334 2.54)
				)
			)
		)
		(zone
			(layer "B.Cu")
			(hatch none 0.5)
			(connect_pads
				(clearance 0)
			)
			(min_thickness 0.25)
			(keepout
				(tracks allowed)
				(vias not_allowed)
				(pads allowed)
				(copperpour not_allowed)
				(footprints allowed)
			)
			(placement
				(enabled no)
				(sheetname "")
			)
			(fill
				(thermal_gap 0.5)
				(thermal_bridge_width 0.5)
				(island_removal_mode 0)
			)
			(polygon
				(pts
					(xy 165.6334 2.54) (xy 165.6334 2.032) (xy 165.2524 2.032) (xy 165.2524 2.54)
				)
			)
		)
	)
)
